(kicad_pcb
	(version 20260206)
	(generator "pcbnew")
	(generator_version "10.0")
	(general
		(thickness 1.6)
		(legacy_teardrops no)
	)
	(paper "A4")
	(title_block
		(title "Bryce Canyon_IOM_M2_16342-2_OCP.brd")
		(comment 1 "Bryce Canyon / footprints 844-850 of 1146")
	)
	(layers
		(0 "F.Cu" signal "TOP")
		(4 "In1.Cu" signal "L2GND")
		(6 "In2.Cu" signal "L3")
		(8 "In3.Cu" signal "L4VCC")
		(10 "In4.Cu" signal "L5VCC")
		(12 "In5.Cu" signal "L6")
		(14 "In6.Cu" signal "L7GND")
		(2 "B.Cu" signal "BOTTOM")
		(9 "F.Adhes" user "F.Adhesive")
		(11 "B.Adhes" user "B.Adhesive")
		(13 "F.Paste" user "Package Geometry/Pastemask Top")
		(15 "B.Paste" user "Package Geometry/Pastemask Bottom")
		(5 "F.SilkS" user "Ref Des/Silkscreen Top")
		(7 "B.SilkS" user "Ref Des/Silkscreen Bottom")
		(1 "F.Mask" user "Board Geometry/Soldermask Top")
		(3 "B.Mask" user "Board Geometry/Soldermask Bottom")
		(17 "Dwgs.User" user "User.Drawings")
		(19 "Cmts.User" user "User.Comments")
		(21 "Eco1.User" user "User.Eco1")
		(23 "Eco2.User" user "User.Eco2")
		(25 "Edge.Cuts" user "Board Geometry/Outline")
		(27 "Margin" user)
		(31 "F.CrtYd" user "Package Geometry/Place Bound Top")
		(29 "B.CrtYd" user "Package Geometry/Place Bound Bottom")
		(35 "F.Fab" user "Ref Des/Assembly Top")
		(33 "B.Fab" user "Ref Des/Assembly Bottom")
	)
	(footprint ""
		(layer "B.Cu")
		(at 32.4866 -159.0802 -90)
		(property "Reference" "R699"
			(at 0 0 90)
			(layer "B.SilkS")
			(hide yes)
			(effects
				(font
					(size 1.27 1.27)
				)
				(justify mirror)
			)
		)
		(property "Value" "4K7R2F-GP"
			(at -0.064008 -3.993896 270)
			(unlocked yes)
			(layer "B.Fab")
			(hide yes)
			(effects
				(font
					(size 1.016 1.016)
					(thickness 0.1524)
				)
				(justify mirror)
			)
		)
		(property "Device Type" "R402H16"
			(at -0.064008 -5.517896 270)
			(unlocked yes)
			(layer "B.Fab")
			(hide yes)
			(effects
				(font
					(size 1.016 1.016)
					(thickness 0.1524)
				)
				(justify mirror)
			)
		)
		(duplicate_pad_numbers_are_jumpers no)
		(fp_line
			(start -0.508 -0.9398)
			(end 0.508 -0.9398)
			(stroke
				(width 0.1524)
				(type default)
			)
			(layer "B.SilkS")
		)
		(fp_line
			(start 0.508 -0.9398)
			(end 0.508 0.9398)
			(stroke
				(width 0.1524)
				(type default)
			)
			(layer "B.SilkS")
		)
		(fp_rect
			(start 0.508 0.9398)
			(end -0.508 -0.9398)
			(stroke
				(width 0)
				(type default)
			)
			(fill no)
			(layer "B.CrtYd")
		)
		(fp_rect
			(start 0.508 0.9398)
			(end -0.508 -0.9398)
			(stroke
				(width 0)
				(type default)
			)
			(fill no)
			(layer "B.Fab")
		)
		(pad "1" smd custom
			(at 0 -0.4445 90)
			(size 0.1397 0.1397)
			(layers "B.Cu" "B.Mask" "B.Paste")
			(net "IOM_TYPE2")
			(options
				(clearance outline)
				(anchor circle)
			)
			(primitives
				(gr_poly
					(pts
						(arc
							(start -0.1778 0.2794)
							(mid -0.249642 0.249642)
							(end -0.2794 0.1778)
						)
						(arc
							(start -0.2794 -0.1778)
							(mid -0.249642 -0.249642)
							(end -0.1778 -0.2794)
						)
						(arc
							(start 0.1778 -0.2794)
							(mid 0.249642 -0.249642)
							(end 0.2794 -0.1778)
						)
						(arc
							(start 0.2794 0.1778)
							(mid 0.249642 0.249642)
							(end 0.1778 0.2794)
						)
					)
					(width 0)
					(fill yes)
				)
			)
		)
		(pad "2" smd custom
			(at 0 0.4445 90)
			(size 0.1397 0.1397)
			(layers "B.Cu" "B.Mask" "B.Paste")
			(net "GND")
			(options
				(clearance outline)
				(anchor circle)
			)
			(primitives
				(gr_poly
					(pts
						(arc
							(start -0.1778 0.2794)
							(mid -0.249642 0.249642)
							(end -0.2794 0.1778)
						)
						(arc
							(start -0.2794 -0.1778)
							(mid -0.249642 -0.249642)
							(end -0.1778 -0.2794)
						)
						(arc
							(start 0.1778 -0.2794)
							(mid 0.249642 -0.249642)
							(end 0.2794 -0.1778)
						)
						(arc
							(start 0.2794 0.1778)
							(mid 0.249642 0.249642)
							(end 0.1778 0.2794)
						)
					)
					(width 0)
					(fill yes)
				)
			)
		)
	)
	(footprint ""
		(layer "B.Cu")
		(at 16.3449 -147.2438 180)
		(property "Reference" "C61"
			(at 0 0 0)
			(layer "B.SilkS")
			(hide yes)
			(effects
				(font
					(size 1.27 1.27)
				)
				(justify mirror)
			)
		)
		(property "Value" "SC1U16V3KX-5GP"
			(at 0 -2.8194 180)
			(unlocked yes)
			(layer "B.Fab")
			(hide yes)
			(effects
				(font
					(size 1.016 1.016)
					(thickness 0.1524)
				)
				(justify mirror)
			)
		)
		(property "Device Type" "C603H36"
			(at 0 -4.3434 180)
			(unlocked yes)
			(layer "B.Fab")
			(hide yes)
			(effects
				(font
					(size 1.016 1.016)
					(thickness 0.1524)
				)
				(justify mirror)
			)
		)
		(duplicate_pad_numbers_are_jumpers no)
		(fp_line
			(start -0.508 0)
			(end 0.508 0)
			(stroke
				(width 0.2032)
				(type default)
			)
			(layer "B.SilkS")
		)
		(fp_rect
			(start 0.5842 1.3335)
			(end -0.5842 -1.3335)
			(stroke
				(width 0)
				(type default)
			)
			(fill no)
			(layer "B.CrtYd")
		)
		(fp_rect
			(start 0.5842 1.3335)
			(end -0.5842 -1.3335)
			(stroke
				(width 0)
				(type default)
			)
			(fill no)
			(layer "B.Fab")
		)
		(pad "1" smd custom
			(at 0 -0.762)
			(size 0.2159 0.2159)
			(layers "B.Cu" "B.Mask" "B.Paste")
			(net "P1V2_STBY")
			(options
				(clearance outline)
				(anchor circle)
			)
			(primitives
				(gr_poly
					(pts
						(arc
							(start -0.3302 0.4318)
							(mid -0.402042 0.402042)
							(end -0.4318 0.3302)
						)
						(arc
							(start -0.4318 -0.3302)
							(mid -0.402042 -0.402042)
							(end -0.3302 -0.4318)
						)
						(arc
							(start 0.3302 -0.4318)
							(mid 0.402042 -0.402042)
							(end 0.4318 -0.3302)
						)
						(arc
							(start 0.4318 0.3302)
							(mid 0.402042 0.402042)
							(end 0.3302 0.4318)
						)
					)
					(width 0)
					(fill yes)
				)
			)
		)
		(pad "2" smd custom
			(at 0 0.762)
			(size 0.2159 0.2159)
			(layers "B.Cu" "B.Mask" "B.Paste")
			(net "GND")
			(options
				(clearance outline)
				(anchor circle)
			)
			(primitives
				(gr_poly
					(pts
						(arc
							(start -0.3302 0.4318)
							(mid -0.402042 0.402042)
							(end -0.4318 0.3302)
						)
						(arc
							(start -0.4318 -0.3302)
							(mid -0.402042 -0.402042)
							(end -0.3302 -0.4318)
						)
						(arc
							(start 0.3302 -0.4318)
							(mid 0.402042 -0.402042)
							(end 0.4318 -0.3302)
						)
						(arc
							(start 0.4318 0.3302)
							(mid 0.402042 0.402042)
							(end 0.3302 0.4318)
						)
					)
					(width 0)
					(fill yes)
				)
			)
		)
	)
	(footprint ""
		(layer "B.Cu")
		(at 90.96248 -138.659616 180)
		(property "Reference" "R721"
			(at 0 0 0)
			(layer "B.SilkS")
			(hide yes)
			(effects
				(font
					(size 1.27 1.27)
				)
				(justify mirror)
			)
		)
		(property "Value" "4K7R2F-GP"
			(at -0.064008 -3.993896 180)
			(unlocked yes)
			(layer "B.Fab")
			(hide yes)
			(effects
				(font
					(size 1.016 1.016)
					(thickness 0.1524)
				)
				(justify mirror)
			)
		)
		(property "Device Type" "R402H16"
			(at -0.064008 -5.517896 180)
			(unlocked yes)
			(layer "B.Fab")
			(hide yes)
			(effects
				(font
					(size 1.016 1.016)
					(thickness 0.1524)
				)
				(justify mirror)
			)
		)
		(duplicate_pad_numbers_are_jumpers no)
		(fp_line
			(start 0.508 -0.9398)
			(end 0.508 0.9398)
			(stroke
				(width 0.1524)
				(type default)
			)
			(layer "B.SilkS")
		)
		(fp_line
			(start -0.508 -0.9398)
			(end 0.508 -0.9398)
			(stroke
				(width 0.1524)
				(type default)
			)
			(layer "B.SilkS")
		)
		(fp_rect
			(start 0.508 0.9398)
			(end -0.508 -0.9398)
			(stroke
				(width 0)
				(type default)
			)
			(fill no)
			(layer "B.CrtYd")
		)
		(fp_rect
			(start 0.508 0.9398)
			(end -0.508 -0.9398)
			(stroke
				(width 0)
				(type default)
			)
			(fill no)
			(layer "B.Fab")
		)
		(pad "1" smd custom
			(at 0 -0.4445)
			(size 0.1397 0.1397)
			(layers "B.Cu" "B.Mask" "B.Paste")
			(net "P3V3_STBY")
			(options
				(clearance outline)
				(anchor circle)
			)
			(primitives
				(gr_poly
					(pts
						(arc
							(start -0.1778 0.2794)
							(mid -0.249642 0.249642)
							(end -0.2794 0.1778)
						)
						(arc
							(start -0.2794 -0.1778)
							(mid -0.249642 -0.249642)
							(end -0.1778 -0.2794)
						)
						(arc
							(start 0.1778 -0.2794)
							(mid 0.249642 -0.249642)
							(end 0.2794 -0.1778)
						)
						(arc
							(start 0.2794 0.1778)
							(mid 0.249642 0.249642)
							(end 0.1778 0.2794)
						)
					)
					(width 0)
					(fill yes)
				)
			)
		)
		(pad "2" smd custom
			(at 0 0.4445)
			(size 0.1397 0.1397)
			(layers "B.Cu" "B.Mask" "B.Paste")
			(net "DEBUG_HDR_UART_SEL")
			(options
				(clearance outline)
				(anchor circle)
			)
			(primitives
				(gr_poly
					(pts
						(arc
							(start -0.1778 0.2794)
							(mid -0.249642 0.249642)
							(end -0.2794 0.1778)
						)
						(arc
							(start -0.2794 -0.1778)
							(mid -0.249642 -0.249642)
							(end -0.1778 -0.2794)
						)
						(arc
							(start 0.1778 -0.2794)
							(mid 0.249642 -0.249642)
							(end 0.2794 -0.1778)
						)
						(arc
							(start 0.2794 0.1778)
							(mid 0.249642 0.249642)
							(end 0.1778 0.2794)
						)
					)
					(width 0)
					(fill yes)
				)
			)
		)
	)
	(footprint ""
		(layer "B.Cu")
		(at 203.273914 -130.370072 180)
		(property "Reference" "C606"
			(at 0 0 0)
			(layer "B.SilkS")
			(hide yes)
			(effects
				(font
					(size 1.27 1.27)
				)
				(justify mirror)
			)
		)
		(property "Value" "SC10U6D3V5KX-4GP"
			(at 0.0762 -6.1214 180)
			(unlocked yes)
			(layer "B.Fab")
			(hide yes)
			(effects
				(font
					(size 1.016 1.016)
					(thickness 0.1524)
				)
				(justify mirror)
			)
		)
		(property "Device Type" "C805H58"
			(at 0.0762 -8.1534 180)
			(unlocked yes)
			(layer "B.Fab")
			(hide yes)
			(effects
				(font
					(size 1.016 1.016)
					(thickness 0.1524)
				)
				(justify mirror)
			)
		)
		(duplicate_pad_numbers_are_jumpers no)
		(fp_line
			(start -0.635 0)
			(end 0.635 0)
			(stroke
				(width 0.508)
				(type default)
			)
			(layer "B.SilkS")
		)
		(fp_rect
			(start 0.9652 1.778)
			(end -0.9652 -1.778)
			(stroke
				(width 0)
				(type default)
			)
			(fill no)
			(layer "B.CrtYd")
		)
		(fp_poly
			(pts
				(xy 0.9652 -1.778) (xy -0.9652 -1.778) (xy -0.9652 1.778) (xy 0.9652 1.778)
			)
			(stroke
				(width 0)
				(type default)
			)
			(fill no)
			(layer "B.Fab")
		)
		(pad "1" smd rect
			(at 0 -0.9652)
			(size 1.397 1.143)
			(layers "B.Cu" "B.Mask" "B.Paste")
			(net "P3V3_M2")
		)
		(pad "2" smd rect
			(at 0 0.9652)
			(size 1.397 1.143)
			(layers "B.Cu" "B.Mask" "B.Paste")
			(net "GND")
		)
	)
	(footprint ""
		(layer "B.Cu")
		(at 47.861474 -155.356052)
		(property "Reference" "R310"
			(at 0 0 0)
			(layer "B.SilkS")
			(hide yes)
			(effects
				(font
					(size 1.27 1.27)
				)
				(justify mirror)
			)
		)
		(property "Value" "4K7R2F-GP"
			(at -0.064008 -3.993896 0)
			(unlocked yes)
			(layer "B.Fab")
			(hide yes)
			(effects
				(font
					(size 1.016 1.016)
					(thickness 0.1524)
				)
				(justify mirror)
			)
		)
		(property "Device Type" "R402H16"
			(at -0.064008 -5.517896 0)
			(unlocked yes)
			(layer "B.Fab")
			(hide yes)
			(effects
				(font
					(size 1.016 1.016)
					(thickness 0.1524)
				)
				(justify mirror)
			)
		)
		(duplicate_pad_numbers_are_jumpers no)
		(fp_line
			(start -0.508 -0.9398)
			(end 0.508 -0.9398)
			(stroke
				(width 0.1524)
				(type default)
			)
			(layer "B.SilkS")
		)
		(fp_line
			(start 0.508 -0.9398)
			(end 0.508 0.9398)
			(stroke
				(width 0.1524)
				(type default)
			)
			(layer "B.SilkS")
		)
		(fp_rect
			(start 0.508 0.9398)
			(end -0.508 -0.9398)
			(stroke
				(width 0)
				(type default)
			)
			(fill no)
			(layer "B.CrtYd")
		)
		(fp_rect
			(start 0.508 0.9398)
			(end -0.508 -0.9398)
			(stroke
				(width 0)
				(type default)
			)
			(fill no)
			(layer "B.Fab")
		)
		(pad "1" smd custom
			(at 0 -0.4445 180)
			(size 0.1397 0.1397)
			(layers "B.Cu" "B.Mask" "B.Paste")
			(net "P3V3_STBY")
			(options
				(clearance outline)
				(anchor circle)
			)
			(primitives
				(gr_poly
					(pts
						(arc
							(start -0.1778 0.2794)
							(mid -0.249642 0.249642)
							(end -0.2794 0.1778)
						)
						(arc
							(start -0.2794 -0.1778)
							(mid -0.249642 -0.249642)
							(end -0.1778 -0.2794)
						)
						(arc
							(start 0.1778 -0.2794)
							(mid 0.249642 -0.249642)
							(end 0.2794 -0.1778)
						)
						(arc
							(start 0.2794 0.1778)
							(mid 0.249642 0.249642)
							(end 0.1778 0.2794)
						)
					)
					(width 0)
					(fill yes)
				)
			)
		)
		(pad "2" smd custom
			(at 0 0.4445 180)
			(size 0.1397 0.1397)
			(layers "B.Cu" "B.Mask" "B.Paste")
			(net "BOARD_REV_1")
			(options
				(clearance outline)
				(anchor circle)
			)
			(primitives
				(gr_poly
					(pts
						(arc
							(start -0.1778 0.2794)
							(mid -0.249642 0.249642)
							(end -0.2794 0.1778)
						)
						(arc
							(start -0.2794 -0.1778)
							(mid -0.249642 -0.249642)
							(end -0.1778 -0.2794)
						)
						(arc
							(start 0.1778 -0.2794)
							(mid 0.249642 -0.249642)
							(end 0.2794 -0.1778)
						)
						(arc
							(start 0.2794 0.1778)
							(mid 0.249642 0.249642)
							(end 0.1778 0.2794)
						)
					)
					(width 0)
					(fill yes)
				)
			)
		)
	)
	(footprint ""
		(layer "B.Cu")
		(at 93.9292 -146.3802 180)
		(property "Reference" "R430"
			(at 0 0 0)
			(layer "B.SilkS")
			(hide yes)
			(effects
				(font
					(size 1.27 1.27)
				)
				(justify mirror)
			)
		)
		(property "Value" "4K7R2F-GP"
			(at -0.064008 -3.993896 180)
			(unlocked yes)
			(layer "B.Fab")
			(hide yes)
			(effects
				(font
					(size 1.016 1.016)
					(thickness 0.1524)
				)
				(justify mirror)
			)
		)
		(property "Device Type" "R402H16"
			(at -0.064008 -5.517896 180)
			(unlocked yes)
			(layer "B.Fab")
			(hide yes)
			(effects
				(font
					(size 1.016 1.016)
					(thickness 0.1524)
				)
				(justify mirror)
			)
		)
		(duplicate_pad_numbers_are_jumpers no)
		(fp_line
			(start 0.508 -0.9398)
			(end 0.508 0.9398)
			(stroke
				(width 0.1524)
				(type default)
			)
			(layer "B.SilkS")
		)
		(fp_line
			(start -0.508 -0.9398)
			(end 0.508 -0.9398)
			(stroke
				(width 0.1524)
				(type default)
			)
			(layer "B.SilkS")
		)
		(fp_rect
			(start 0.508 0.9398)
			(end -0.508 -0.9398)
			(stroke
				(width 0)
				(type default)
			)
			(fill no)
			(layer "B.CrtYd")
		)
		(fp_rect
			(start 0.508 0.9398)
			(end -0.508 -0.9398)
			(stroke
				(width 0)
				(type default)
			)
			(fill no)
			(layer "B.Fab")
		)
		(pad "1" smd custom
			(at 0 -0.4445)
			(size 0.1397 0.1397)
			(layers "B.Cu" "B.Mask" "B.Paste")
			(net "TCA9555_A2")
			(options
				(clearance outline)
				(anchor circle)
			)
			(primitives
				(gr_poly
					(pts
						(arc
							(start -0.1778 0.2794)
							(mid -0.249642 0.249642)
							(end -0.2794 0.1778)
						)
						(arc
							(start -0.2794 -0.1778)
							(mid -0.249642 -0.249642)
							(end -0.1778 -0.2794)
						)
						(arc
							(start 0.1778 -0.2794)
							(mid 0.249642 -0.249642)
							(end 0.2794 -0.1778)
						)
						(arc
							(start 0.2794 0.1778)
							(mid 0.249642 0.249642)
							(end 0.1778 0.2794)
						)
					)
					(width 0)
					(fill yes)
				)
			)
		)
		(pad "2" smd custom
			(at 0 0.4445)
			(size 0.1397 0.1397)
			(layers "B.Cu" "B.Mask" "B.Paste")
			(net "GND")
			(options
				(clearance outline)
				(anchor circle)
			)
			(primitives
				(gr_poly
					(pts
						(arc
							(start -0.1778 0.2794)
							(mid -0.249642 0.249642)
							(end -0.2794 0.1778)
						)
						(arc
							(start -0.2794 -0.1778)
							(mid -0.249642 -0.249642)
							(end -0.1778 -0.2794)
						)
						(arc
							(start 0.1778 -0.2794)
							(mid 0.249642 -0.249642)
							(end 0.2794 -0.1778)
						)
						(arc
							(start 0.2794 0.1778)
							(mid 0.249642 0.249642)
							(end 0.1778 0.2794)
						)
					)
					(width 0)
					(fill yes)
				)
			)
		)
	)
	(footprint ""
		(layer "B.Cu")
		(at 177.5587 -118.690644 180)
		(property "Reference" "U83"
			(at 0 0 0)
			(layer "B.SilkS")
			(hide yes)
			(effects
				(font
					(size 1.27 1.27)
				)
				(justify mirror)
			)
		)
		(property "Value" "PCA9306DCTT-GP"
			(at 0 -11.6332 180)
			(unlocked yes)
			(layer "B.Fab")
			(hide yes)
			(effects
				(font
					(size 1.016 1.016)
					(thickness 0.1524)
				)
				(justify mirror)
			)
		)
		(property "Device Type" "SSOIC8H52"
			(at 0 -13.1572 180)
			(unlocked yes)
			(layer "B.Fab")
			(hide yes)
			(effects
				(font
					(size 1.016 1.016)
					(thickness 0.1524)
				)
				(justify mirror)
			)
		)
		(duplicate_pad_numbers_are_jumpers no)
		(fp_line
			(start 1.7018 -0.5842)
			(end 1.7018 2.286)
			(stroke
				(width 0.1524)
				(type default)
			)
			(layer "B.SilkS")
		)
		(fp_line
			(start 1.7018 -0.5842)
			(end -1.0668 -0.5842)
			(stroke
				(width 0.1524)
				(type default)
			)
			(layer "B.SilkS")
		)
		(fp_line
			(start 1.524 0.5842)
			(end 1.524 2.286)
			(stroke
				(width 0.508)
				(type default)
			)
			(layer "B.SilkS")
		)
		(fp_line
			(start 1.397 0)
			(end 1.7018 0.3048)
			(stroke
				(width 0.1524)
				(type default)
			)
			(layer "B.SilkS")
		)
		(fp_line
			(start 1.397 0)
			(end 1.7018 -0.3048)
			(stroke
				(width 0.1524)
				(type default)
			)
			(layer "B.SilkS")
		)
		(fp_line
			(start -1.0668 0.5842)
			(end 1.524 0.5842)
			(stroke
				(width 0.1524)
				(type default)
			)
			(layer "B.SilkS")
		)
		(fp_line
			(start -1.0668 -0.5842)
			(end -1.0668 0.5842)
			(stroke
				(width 0.1524)
				(type default)
			)
			(layer "B.SilkS")
		)
		(fp_poly
			(pts
				(xy 1.1684 -0.5842) (xy -1.0668 -0.5842) (xy -1.0668 0.5842) (xy 1.1684 0.5842)
			)
			(stroke
				(width 0)
				(type default)
			)
			(fill yes)
			(layer "B.SilkS")
		)
		(fp_poly
			(pts
				(xy 1.778 2.54) (xy -1.778 2.54) (xy -1.778 -2.54) (xy 1.778 -2.54)
			)
			(stroke
				(width 0)
				(type default)
			)
			(fill no)
			(layer "B.CrtYd")
		)
		(fp_poly
			(pts
				(xy 1.778 -2.54) (xy -1.778 -2.54) (xy -1.778 2.54) (xy 1.778 2.54)
			)
			(stroke
				(width 0)
				(type default)
			)
			(fill no)
			(layer "B.Fab")
		)
		(pad "1" smd rect
			(at 0.97536 1.6256)
			(size 0.3556 1.524)
			(layers "B.Cu" "B.Mask" "B.Paste")
			(net "GND")
		)
		(pad "2" smd rect
			(at 0.32512 1.6256)
			(size 0.3556 1.524)
			(layers "B.Cu" "B.Mask" "B.Paste")
			(net "P1V8_STBY")
		)
		(pad "3" smd rect
			(at -0.32512 1.6256)
			(size 0.3556 1.524)
			(layers "B.Cu" "B.Mask" "B.Paste")
			(net "I2C_M2_2_1V8_SCL")
		)
		(pad "4" smd rect
			(at -0.97536 1.6256)
			(size 0.3556 1.524)
			(layers "B.Cu" "B.Mask" "B.Paste")
			(net "I2C_M2_2_1V8_SDA")
		)
		(pad "5" smd rect
			(at -0.97536 -1.6256)
			(size 0.3556 1.524)
			(layers "B.Cu" "B.Mask" "B.Paste")
			(net "I2C_M2_2_SDA")
		)
		(pad "6" smd rect
			(at -0.32512 -1.6256)
			(size 0.3556 1.524)
			(layers "B.Cu" "B.Mask" "B.Paste")
			(net "I2C_M2_2_SCL")
		)
		(pad "7" smd rect
			(at 0.32512 -1.6256)
			(size 0.3556 1.524)
			(layers "B.Cu" "B.Mask" "B.Paste")
			(net "U83_VREF2")
		)
		(pad "8" smd rect
			(at 0.97536 -1.6256)
			(size 0.3556 1.524)
			(layers "B.Cu" "B.Mask" "B.Paste")
			(net "U83_VREF2")
		)
	)
)
